(kicad_pcb
	(version 20260206)
	(generator "pcbnew")
	(generator_version "10.0")
	(general
		(thickness 1.6)
		(legacy_teardrops no)
	)
	(paper "A4")
	(title_block
		(title "v1-chassis-manager — T6M_CM_d_v01_1031_1645.brd")
		(comment 1 "Open CloudServer (Microsoft) / footprints 878-887 of 2512")
	)
	(layers
		(0 "F.Cu" signal "TOP")
		(4 "In1.Cu" signal "GND1")
		(6 "In2.Cu" signal "IN1")
		(8 "In3.Cu" signal "VCC1")
		(10 "In4.Cu" signal "VCC2")
		(12 "In5.Cu" signal "GND2")
		(14 "In6.Cu" signal "IN2")
		(16 "In7.Cu" signal "IN3")
		(18 "In8.Cu" signal "GND3")
		(2 "B.Cu" signal "BOTTOM")
		(9 "F.Adhes" user "F.Adhesive")
		(11 "B.Adhes" user "B.Adhesive")
		(13 "F.Paste" user "Package Geometry/Pastemask Top")
		(15 "B.Paste" user "Package Geometry/Pastemask Bottom")
		(5 "F.SilkS" user "Ref Des/Silkscreen Top")
		(7 "B.SilkS" user "Ref Des/Silkscreen Bottom")
		(1 "F.Mask" user "Board Geometry/Soldermask Top")
		(3 "B.Mask" user "Board Geometry/Soldermask Bottom")
		(17 "Dwgs.User" user "User.Drawings")
		(19 "Cmts.User" user "User.Comments")
		(21 "Eco1.User" user "User.Eco1")
		(23 "Eco2.User" user "User.Eco2")
		(25 "Edge.Cuts" user "Board Geometry/Outline")
		(27 "Margin" user)
		(31 "F.CrtYd" user "Package Geometry/Place Bound Top")
		(29 "B.CrtYd" user "Package Geometry/Place Bound Bottom")
		(35 "F.Fab" user "Ref Des/Assembly Top")
		(33 "B.Fab" user "Ref Des/Assembly Bottom")
	)
	(footprint ""
		(layer "F.Cu")
		(at 75.67676 -185.205624 90)
		(property "Reference" "C701"
			(at 4.006088 -1.429258 90)
			(unlocked yes)
			(layer "F.SilkS")
			(effects
				(font
					(size 0.7874 0.5842)
					(thickness 0.1524)
				)
				(justify left)
			)
		)
		(property "Value" ""
			(at 0 0 90)
			(layer "F.Fab")
			(effects
				(font
					(size 1.27 1.27)
				)
			)
		)
		(duplicate_pad_numbers_are_jumpers no)
		(fp_line
			(start 0.7874 -0.4064)
			(end 0.7874 0.4064)
			(stroke
				(width 0.1524)
				(type default)
			)
			(layer "F.SilkS")
		)
		(fp_line
			(start -0.7874 -0.4064)
			(end 0.7874 -0.4064)
			(stroke
				(width 0.1524)
				(type default)
			)
			(layer "F.SilkS")
		)
		(fp_line
			(start 0 0.381)
			(end 0 -0.381)
			(stroke
				(width 0.1524)
				(type default)
			)
			(layer "F.SilkS")
		)
		(fp_line
			(start 0.7874 0.4064)
			(end -0.7874 0.4064)
			(stroke
				(width 0.1524)
				(type default)
			)
			(layer "F.SilkS")
		)
		(fp_line
			(start -0.7874 0.4064)
			(end -0.7874 -0.4064)
			(stroke
				(width 0.1524)
				(type default)
			)
			(layer "F.SilkS")
		)
		(fp_poly
			(pts
				(xy -0.5334 0.254) (xy -0.635 0.254) (xy -0.635 0.2286) (xy -0.635 -0.254) (xy -0.5334 -0.254) (xy -0.5334 -0.2794)
				(xy 0.5334 -0.2794) (xy 0.5334 -0.254) (xy 0.635 -0.254) (xy 0.635 0.254) (xy 0.5334 0.254) (xy 0.5334 0.2794)
				(xy -0.508 0.2794) (xy -0.5334 0.2794)
			)
			(stroke
				(width 0)
				(type default)
			)
			(fill no)
			(layer "F.CrtYd")
		)
		(pad "1" smd rect
			(at 0.40005 0 90)
			(size 0.4572 0.508)
			(layers "F.Cu" "F.Mask" "F.Paste")
			(net "UART_T4_NODE2_RXD")
		)
		(pad "2" smd rect
			(at -0.40005 0 90)
			(size 0.4572 0.508)
			(layers "F.Cu" "F.Mask" "F.Paste")
			(net "GND")
		)
	)
	(footprint ""
		(layer "F.Cu")
		(at 159.652208 -73.271126)
		(property "Reference" "PR9"
			(at -3.902456 -2.833878 0)
			(unlocked yes)
			(layer "F.SilkS")
			(effects
				(font
					(size 0.7874 0.5842)
					(thickness 0.1524)
				)
				(justify left)
			)
		)
		(property "Value" ""
			(at 0 0 0)
			(layer "F.Fab")
			(effects
				(font
					(size 1.27 1.27)
				)
			)
		)
		(duplicate_pad_numbers_are_jumpers no)
		(fp_line
			(start -0.7874 -0.4064)
			(end 0.7874 -0.4064)
			(stroke
				(width 0.1524)
				(type default)
			)
			(layer "F.SilkS")
		)
		(fp_line
			(start -0.7874 0.4064)
			(end -0.7874 -0.4064)
			(stroke
				(width 0.1524)
				(type default)
			)
			(layer "F.SilkS")
		)
		(fp_line
			(start 0.7874 -0.4064)
			(end 0.7874 0.4064)
			(stroke
				(width 0.1524)
				(type default)
			)
			(layer "F.SilkS")
		)
		(fp_line
			(start 0.7874 0.4064)
			(end -0.7874 0.4064)
			(stroke
				(width 0.1524)
				(type default)
			)
			(layer "F.SilkS")
		)
		(fp_poly
			(pts
				(xy -0.508 0.2794) (xy -0.508 0.2286) (xy -0.635 0.2286) (xy -0.635 -0.254) (xy -0.5334 -0.254)
				(xy -0.5334 -0.2794) (xy 0.5334 -0.2794) (xy 0.5334 -0.254) (xy 0.635 -0.254) (xy 0.635 0.254) (xy 0.5334 0.254)
				(xy 0.5334 0.2794)
			)
			(stroke
				(width 0)
				(type default)
			)
			(fill no)
			(layer "F.CrtYd")
		)
		(pad "1" smd rect
			(at 0.40005 0)
			(size 0.4572 0.508)
			(layers "F.Cu" "F.Mask" "F.Paste")
			(net "P1V0_ADJ")
		)
		(pad "2" smd rect
			(at -0.40005 0)
			(size 0.4572 0.508)
			(layers "F.Cu" "F.Mask" "F.Paste")
			(net "P1V0_ADJ_S")
		)
	)
	(footprint ""
		(layer "F.Cu")
		(at 148.19376 -185.205624 -90)
		(property "Reference" "R990"
			(at -4.768088 -0.259588 90)
			(unlocked yes)
			(layer "F.SilkS")
			(effects
				(font
					(size 0.7874 0.5842)
					(thickness 0.1524)
				)
				(justify left)
			)
		)
		(property "Value" ""
			(at 0 0 270)
			(layer "F.Fab")
			(effects
				(font
					(size 1.27 1.27)
				)
			)
		)
		(duplicate_pad_numbers_are_jumpers no)
		(fp_line
			(start -0.7874 0.4064)
			(end -0.7874 -0.4064)
			(stroke
				(width 0.1524)
				(type default)
			)
			(layer "F.SilkS")
		)
		(fp_line
			(start 0.7874 0.4064)
			(end -0.7874 0.4064)
			(stroke
				(width 0.1524)
				(type default)
			)
			(layer "F.SilkS")
		)
		(fp_line
			(start -0.7874 -0.4064)
			(end 0.7874 -0.4064)
			(stroke
				(width 0.1524)
				(type default)
			)
			(layer "F.SilkS")
		)
		(fp_line
			(start 0.7874 -0.4064)
			(end 0.7874 0.4064)
			(stroke
				(width 0.1524)
				(type default)
			)
			(layer "F.SilkS")
		)
		(fp_poly
			(pts
				(xy -0.508 0.2794) (xy -0.508 0.2286) (xy -0.635 0.2286) (xy -0.635 -0.254) (xy -0.5334 -0.254)
				(xy -0.5334 -0.2794) (xy 0.5334 -0.2794) (xy 0.5334 -0.254) (xy 0.635 -0.254) (xy 0.635 0.254) (xy 0.5334 0.254)
				(xy 0.5334 0.2794)
			)
			(stroke
				(width 0)
				(type default)
			)
			(fill no)
			(layer "F.CrtYd")
		)
		(pad "1" smd rect
			(at 0.40005 0 270)
			(size 0.4572 0.508)
			(layers "F.Cu" "F.Mask" "F.Paste")
			(net "UART_T12_NODE2_TXD")
		)
		(pad "2" smd rect
			(at -0.40005 0 270)
			(size 0.4572 0.508)
			(layers "F.Cu" "F.Mask" "F.Paste")
			(net "UART_T12_NODE2_TXD_R")
		)
	)
	(footprint ""
		(layer "F.Cu")
		(at 148.076158 -174.250604 180)
		(property "Reference" "C904"
			(at 0.048514 -3.781806 90)
			(unlocked yes)
			(layer "F.SilkS")
			(effects
				(font
					(size 0.7874 0.5842)
					(thickness 0.1524)
				)
				(justify left)
			)
		)
		(property "Value" ""
			(at 0 0 180)
			(layer "F.Fab")
			(effects
				(font
					(size 1.27 1.27)
				)
			)
		)
		(duplicate_pad_numbers_are_jumpers no)
		(fp_line
			(start 0.7874 0.4064)
			(end -0.7874 0.4064)
			(stroke
				(width 0.1524)
				(type default)
			)
			(layer "F.SilkS")
		)
		(fp_line
			(start 0.7874 -0.4064)
			(end 0.7874 0.4064)
			(stroke
				(width 0.1524)
				(type default)
			)
			(layer "F.SilkS")
		)
		(fp_line
			(start 0 0.381)
			(end 0 -0.381)
			(stroke
				(width 0.1524)
				(type default)
			)
			(layer "F.SilkS")
		)
		(fp_line
			(start -0.7874 0.4064)
			(end -0.7874 -0.4064)
			(stroke
				(width 0.1524)
				(type default)
			)
			(layer "F.SilkS")
		)
		(fp_line
			(start -0.7874 -0.4064)
			(end 0.7874 -0.4064)
			(stroke
				(width 0.1524)
				(type default)
			)
			(layer "F.SilkS")
		)
		(fp_poly
			(pts
				(xy -0.5334 0.254) (xy -0.635 0.254) (xy -0.635 0.2286) (xy -0.635 -0.254) (xy -0.5334 -0.254) (xy -0.5334 -0.2794)
				(xy 0.5334 -0.2794) (xy 0.5334 -0.254) (xy 0.635 -0.254) (xy 0.635 0.254) (xy 0.5334 0.254) (xy 0.5334 0.2794)
				(xy -0.508 0.2794) (xy -0.5334 0.2794)
			)
			(stroke
				(width 0)
				(type default)
			)
			(fill no)
			(layer "F.CrtYd")
		)
		(pad "1" smd rect
			(at 0.40005 0 180)
			(size 0.4572 0.508)
			(layers "F.Cu" "F.Mask" "F.Paste")
			(net "P3V3_NODE1")
		)
		(pad "2" smd rect
			(at -0.40005 0 180)
			(size 0.4572 0.508)
			(layers "F.Cu" "F.Mask" "F.Paste")
			(net "GND")
		)
	)
	(footprint ""
		(layer "F.Cu")
		(at 125.407928 -61.690758)
		(property "Reference" "C335"
			(at -4.630928 0.01397 0)
			(unlocked yes)
			(layer "F.SilkS")
			(effects
				(font
					(size 0.7874 0.5842)
					(thickness 0.1524)
				)
				(justify left)
			)
		)
		(property "Value" ""
			(at 0 0 0)
			(layer "F.Fab")
			(effects
				(font
					(size 1.27 1.27)
				)
			)
		)
		(duplicate_pad_numbers_are_jumpers no)
		(fp_line
			(start -0.7874 -0.4064)
			(end 0.7874 -0.4064)
			(stroke
				(width 0.1524)
				(type default)
			)
			(layer "F.SilkS")
		)
		(fp_line
			(start -0.7874 0.4064)
			(end -0.7874 -0.4064)
			(stroke
				(width 0.1524)
				(type default)
			)
			(layer "F.SilkS")
		)
		(fp_line
			(start 0 0.381)
			(end 0 -0.381)
			(stroke
				(width 0.1524)
				(type default)
			)
			(layer "F.SilkS")
		)
		(fp_line
			(start 0.7874 -0.4064)
			(end 0.7874 0.4064)
			(stroke
				(width 0.1524)
				(type default)
			)
			(layer "F.SilkS")
		)
		(fp_line
			(start 0.7874 0.4064)
			(end -0.7874 0.4064)
			(stroke
				(width 0.1524)
				(type default)
			)
			(layer "F.SilkS")
		)
		(fp_poly
			(pts
				(xy -0.5334 0.254) (xy -0.635 0.254) (xy -0.635 0.2286) (xy -0.635 -0.254) (xy -0.5334 -0.254) (xy -0.5334 -0.2794)
				(xy 0.5334 -0.2794) (xy 0.5334 -0.254) (xy 0.635 -0.254) (xy 0.635 0.254) (xy 0.5334 0.254) (xy 0.5334 0.2794)
				(xy -0.508 0.2794) (xy -0.5334 0.2794)
			)
			(stroke
				(width 0)
				(type default)
			)
			(fill no)
			(layer "F.CrtYd")
		)
		(pad "1" smd rect
			(at 0.40005 0)
			(size 0.4572 0.508)
			(layers "F.Cu" "F.Mask" "F.Paste")
			(net "P3V3_NODE1")
		)
		(pad "2" smd rect
			(at -0.40005 0)
			(size 0.4572 0.508)
			(layers "F.Cu" "F.Mask" "F.Paste")
			(net "GND")
		)
	)
	(footprint ""
		(layer "F.Cu")
		(at 75.174856 -120.964706)
		(property "Reference" "C203"
			(at -4.55422 0.23114 0)
			(unlocked yes)
			(layer "F.SilkS")
			(effects
				(font
					(size 0.7874 0.5842)
					(thickness 0.1524)
				)
				(justify left)
			)
		)
		(property "Value" ""
			(at 0 0 0)
			(layer "F.Fab")
			(effects
				(font
					(size 1.27 1.27)
				)
			)
		)
		(duplicate_pad_numbers_are_jumpers no)
		(fp_line
			(start -0.7874 -0.4064)
			(end 0.7874 -0.4064)
			(stroke
				(width 0.1524)
				(type default)
			)
			(layer "F.SilkS")
		)
		(fp_line
			(start -0.7874 0.4064)
			(end -0.7874 -0.4064)
			(stroke
				(width 0.1524)
				(type default)
			)
			(layer "F.SilkS")
		)
		(fp_line
			(start 0 0.381)
			(end 0 -0.381)
			(stroke
				(width 0.1524)
				(type default)
			)
			(layer "F.SilkS")
		)
		(fp_line
			(start 0.7874 -0.4064)
			(end 0.7874 0.4064)
			(stroke
				(width 0.1524)
				(type default)
			)
			(layer "F.SilkS")
		)
		(fp_line
			(start 0.7874 0.4064)
			(end -0.7874 0.4064)
			(stroke
				(width 0.1524)
				(type default)
			)
			(layer "F.SilkS")
		)
		(fp_poly
			(pts
				(xy -0.5334 0.254) (xy -0.635 0.254) (xy -0.635 0.2286) (xy -0.635 -0.254) (xy -0.5334 -0.254) (xy -0.5334 -0.2794)
				(xy 0.5334 -0.2794) (xy 0.5334 -0.254) (xy 0.635 -0.254) (xy 0.635 0.254) (xy 0.5334 0.254) (xy 0.5334 0.2794)
				(xy -0.508 0.2794) (xy -0.5334 0.2794)
			)
			(stroke
				(width 0)
				(type default)
			)
			(fill no)
			(layer "F.CrtYd")
		)
		(pad "1" smd rect
			(at 0.40005 0)
			(size 0.4572 0.508)
			(layers "F.Cu" "F.Mask" "F.Paste")
			(net "P2E_CPU_BMC_NODE1_RX_DN")
		)
		(pad "2" smd rect
			(at -0.40005 0)
			(size 0.4572 0.508)
			(layers "F.Cu" "F.Mask" "F.Paste")
			(net "P2E_CPU_BMC_NODE1_RX_C_DN")
		)
	)
	(footprint ""
		(layer "F.Cu")
		(at 14.359382 -156.186378 180)
		(property "Reference" "R1273"
			(at 1.619504 -2.243074 0)
			(unlocked yes)
			(layer "F.SilkS")
			(effects
				(font
					(size 0.7874 0.5842)
					(thickness 0.1524)
				)
				(justify left)
			)
		)
		(property "Value" ""
			(at 0 0 180)
			(layer "F.Fab")
			(effects
				(font
					(size 1.27 1.27)
				)
			)
		)
		(duplicate_pad_numbers_are_jumpers no)
		(fp_line
			(start 0.7874 0.4064)
			(end -0.7874 0.4064)
			(stroke
				(width 0.1524)
				(type default)
			)
			(layer "F.SilkS")
		)
		(fp_line
			(start 0.7874 -0.4064)
			(end 0.7874 0.4064)
			(stroke
				(width 0.1524)
				(type default)
			)
			(layer "F.SilkS")
		)
		(fp_line
			(start -0.7874 0.4064)
			(end -0.7874 -0.4064)
			(stroke
				(width 0.1524)
				(type default)
			)
			(layer "F.SilkS")
		)
		(fp_line
			(start -0.7874 -0.4064)
			(end 0.7874 -0.4064)
			(stroke
				(width 0.1524)
				(type default)
			)
			(layer "F.SilkS")
		)
		(fp_poly
			(pts
				(xy -0.508 0.2794) (xy -0.508 0.2286) (xy -0.635 0.2286) (xy -0.635 -0.254) (xy -0.5334 -0.254)
				(xy -0.5334 -0.2794) (xy 0.5334 -0.2794) (xy 0.5334 -0.254) (xy 0.635 -0.254) (xy 0.635 0.254) (xy 0.5334 0.254)
				(xy 0.5334 0.2794)
			)
			(stroke
				(width 0)
				(type default)
			)
			(fill no)
			(layer "F.CrtYd")
		)
		(pad "1" smd rect
			(at 0.40005 0 180)
			(size 0.4572 0.508)
			(layers "F.Cu" "F.Mask" "F.Paste")
			(net "N54065132")
		)
		(pad "2" smd rect
			(at -0.40005 0 180)
			(size 0.4572 0.508)
			(layers "F.Cu" "F.Mask" "F.Paste")
			(net "LAN1_P1_R")
		)
	)
	(footprint ""
		(layer "F.Cu")
		(at 68.068698 -17.679416 90)
		(property "Reference" "C164"
			(at -2.143252 -2.04597 90)
			(unlocked yes)
			(layer "F.SilkS")
			(effects
				(font
					(size 0.7874 0.5842)
					(thickness 0.1524)
				)
				(justify left)
			)
		)
		(property "Value" ""
			(at 0 0 90)
			(layer "F.Fab")
			(effects
				(font
					(size 1.27 1.27)
				)
			)
		)
		(duplicate_pad_numbers_are_jumpers no)
		(fp_line
			(start 0.7874 -0.4064)
			(end 0.7874 0.4064)
			(stroke
				(width 0.1524)
				(type default)
			)
			(layer "F.SilkS")
		)
		(fp_line
			(start -0.7874 -0.4064)
			(end 0.7874 -0.4064)
			(stroke
				(width 0.1524)
				(type default)
			)
			(layer "F.SilkS")
		)
		(fp_line
			(start 0 0.381)
			(end 0 -0.381)
			(stroke
				(width 0.1524)
				(type default)
			)
			(layer "F.SilkS")
		)
		(fp_line
			(start 0.7874 0.4064)
			(end -0.7874 0.4064)
			(stroke
				(width 0.1524)
				(type default)
			)
			(layer "F.SilkS")
		)
		(fp_line
			(start -0.7874 0.4064)
			(end -0.7874 -0.4064)
			(stroke
				(width 0.1524)
				(type default)
			)
			(layer "F.SilkS")
		)
		(fp_poly
			(pts
				(xy -0.5334 0.254) (xy -0.635 0.254) (xy -0.635 0.2286) (xy -0.635 -0.254) (xy -0.5334 -0.254) (xy -0.5334 -0.2794)
				(xy 0.5334 -0.2794) (xy 0.5334 -0.254) (xy 0.635 -0.254) (xy 0.635 0.254) (xy 0.5334 0.254) (xy 0.5334 0.2794)
				(xy -0.508 0.2794) (xy -0.5334 0.2794)
			)
			(stroke
				(width 0)
				(type default)
			)
			(fill no)
			(layer "F.CrtYd")
		)
		(pad "1" smd rect
			(at 0.40005 0 90)
			(size 0.4572 0.508)
			(layers "F.Cu" "F.Mask" "F.Paste")
			(net "PV_VDDR_NODE1")
		)
		(pad "2" smd rect
			(at -0.40005 0 90)
			(size 0.4572 0.508)
			(layers "F.Cu" "F.Mask" "F.Paste")
			(net "GND")
		)
	)
	(footprint ""
		(layer "F.Cu")
		(at 117.243352 -140.217652 90)
		(property "Reference" "PR63"
			(at 3.640328 2.781554 90)
			(unlocked yes)
			(layer "F.SilkS")
			(effects
				(font
					(size 0.7874 0.5842)
					(thickness 0.1524)
				)
				(justify left)
			)
		)
		(property "Value" ""
			(at 0 0 90)
			(layer "F.Fab")
			(effects
				(font
					(size 1.27 1.27)
				)
			)
		)
		(duplicate_pad_numbers_are_jumpers no)
		(fp_line
			(start 0.7874 -0.4064)
			(end 0.7874 0.4064)
			(stroke
				(width 0.1524)
				(type default)
			)
			(layer "F.SilkS")
		)
		(fp_line
			(start -0.7874 -0.4064)
			(end 0.7874 -0.4064)
			(stroke
				(width 0.1524)
				(type default)
			)
			(layer "F.SilkS")
		)
		(fp_line
			(start 0.7874 0.4064)
			(end -0.7874 0.4064)
			(stroke
				(width 0.1524)
				(type default)
			)
			(layer "F.SilkS")
		)
		(fp_line
			(start -0.7874 0.4064)
			(end -0.7874 -0.4064)
			(stroke
				(width 0.1524)
				(type default)
			)
			(layer "F.SilkS")
		)
		(fp_poly
			(pts
				(xy -0.508 0.2794) (xy -0.508 0.2286) (xy -0.635 0.2286) (xy -0.635 -0.254) (xy -0.5334 -0.254)
				(xy -0.5334 -0.2794) (xy 0.5334 -0.2794) (xy 0.5334 -0.254) (xy 0.635 -0.254) (xy 0.635 0.254) (xy 0.5334 0.254)
				(xy 0.5334 0.2794)
			)
			(stroke
				(width 0)
				(type default)
			)
			(fill no)
			(layer "F.CrtYd")
		)
		(pad "1" smd rect
			(at 0.40005 0 90)
			(size 0.4572 0.508)
			(layers "F.Cu" "F.Mask" "F.Paste")
			(net "VSENSE_VCC_CPU_NODE1")
		)
		(pad "2" smd rect
			(at -0.40005 0 90)
			(size 0.4572 0.508)
			(layers "F.Cu" "F.Mask" "F.Paste")
			(net "PV_VCCP_NODE1")
		)
	)
	(footprint ""
		(layer "F.Cu")
		(at 100.168456 -4.449826)
		(property "Reference" "C134"
			(at 0.613918 1.10363 0)
			(unlocked yes)
			(layer "F.SilkS")
			(effects
				(font
					(size 0.7874 0.5842)
					(thickness 0.1524)
				)
				(justify left)
			)
		)
		(property "Value" ""
			(at 0 0 0)
			(layer "F.Fab")
			(effects
				(font
					(size 1.27 1.27)
				)
			)
		)
		(duplicate_pad_numbers_are_jumpers no)
		(fp_line
			(start -0.7874 -0.4064)
			(end 0.7874 -0.4064)
			(stroke
				(width 0.1524)
				(type default)
			)
			(layer "F.SilkS")
		)
		(fp_line
			(start -0.7874 0.4064)
			(end -0.7874 -0.4064)
			(stroke
				(width 0.1524)
				(type default)
			)
			(layer "F.SilkS")
		)
		(fp_line
			(start 0 0.381)
			(end 0 -0.381)
			(stroke
				(width 0.1524)
				(type default)
			)
			(layer "F.SilkS")
		)
		(fp_line
			(start 0.7874 -0.4064)
			(end 0.7874 0.4064)
			(stroke
				(width 0.1524)
				(type default)
			)
			(layer "F.SilkS")
		)
		(fp_line
			(start 0.7874 0.4064)
			(end -0.7874 0.4064)
			(stroke
				(width 0.1524)
				(type default)
			)
			(layer "F.SilkS")
		)
		(fp_poly
			(pts
				(xy -0.5334 0.254) (xy -0.635 0.254) (xy -0.635 0.2286) (xy -0.635 -0.254) (xy -0.5334 -0.254) (xy -0.5334 -0.2794)
				(xy 0.5334 -0.2794) (xy 0.5334 -0.254) (xy 0.635 -0.254) (xy 0.635 0.254) (xy 0.5334 0.254) (xy 0.5334 0.2794)
				(xy -0.508 0.2794) (xy -0.5334 0.2794)
			)
			(stroke
				(width 0)
				(type default)
			)
			(fill no)
			(layer "F.CrtYd")
		)
		(pad "1" smd rect
			(at 0.40005 0)
			(size 0.4572 0.508)
			(layers "F.Cu" "F.Mask" "F.Paste")
			(net "GND")
		)
		(pad "2" smd rect
			(at -0.40005 0)
			(size 0.4572 0.508)
			(layers "F.Cu" "F.Mask" "F.Paste")
			(net "P3V3_NODE1")
		)
	)
)
